# T6G (Grand Teton) — schematic netlist excerpt (pin names and nets, part order shuffled) for the footprints in the layout excerpt that follows; sources: Cadence DE-HDL packaged netlist, KiCad conversion of 04192023_DAF0TMB3IC0_F0TG_MB_C_brd_V02_OCP.brd

PC80  Q_CAP  2.2UF 10V 10% X6S  pkg C0402  page 201 : A = PVDDCR_CPU1_P0_VCC2 ; B = GND
C2262  Q_CAP  22UF 4V 20% X6S  pkg C0402  page 72 : A = PVDD11_S3_P1 ; B = GND

(kicad_pcb
	(version 20260206)
	(generator "pcbnew")
	(generator_version "10.0")
	(general
		(thickness 1.6)
		(legacy_teardrops no)
	)
	(paper "A4")
	(title_block
		(title "04192023_DAF0TMB3IC0_F0TG_MB_C_brd_V02_OCP.brd")
		(comment 1 "Grand Teton / footprints 1892-1893 of 8354")
	)
	(layers
		(0 "F.Cu" signal "TOP")
		(4 "In1.Cu" signal "GND")
		(6 "In2.Cu" signal "IN1")
		(8 "In3.Cu" signal "GND1")
		(10 "In4.Cu" signal "IN2")
		(12 "In5.Cu" signal "GND2")
		(14 "In6.Cu" signal "IN3")
		(16 "In7.Cu" signal "GND3")
		(18 "In8.Cu" signal "VCC")
		(20 "In9.Cu" signal "VCC1")
		(22 "In10.Cu" signal "GND4")
		(24 "In11.Cu" signal "IN4")
		(26 "In12.Cu" signal "GND5")
		(28 "In13.Cu" signal "IN5")
		(30 "In14.Cu" signal "GND6")
		(32 "In15.Cu" signal "IN6")
		(34 "In16.Cu" signal "GND7")
		(2 "B.Cu" signal "BOTTOM")
		(9 "F.Adhes" user "F.Adhesive")
		(11 "B.Adhes" user "B.Adhesive")
		(13 "F.Paste" user "Package Geometry/Pastemask Top")
		(15 "B.Paste" user "Package Geometry/Pastemask Bottom")
		(5 "F.SilkS" user "Ref Des/Silkscreen Top")
		(7 "B.SilkS" user "Ref Des/Silkscreen Bottom")
		(1 "F.Mask" user "Board Geometry/Soldermask Top")
		(3 "B.Mask" user "Board Geometry/Soldermask Bottom")
		(17 "Dwgs.User" user "User.Drawings")
		(19 "Cmts.User" user "User.Comments")
		(21 "Eco1.User" user "User.Eco1")
		(23 "Eco2.User" user "User.Eco2")
		(25 "Edge.Cuts" user "Board Geometry/Outline")
		(27 "Margin" user)
		(31 "F.CrtYd" user "Package Geometry/Place Bound Top")
		(29 "B.CrtYd" user "Package Geometry/Place Bound Bottom")
		(35 "F.Fab" user "Ref Des/Assembly Top")
		(33 "B.Fab" user "Ref Des/Assembly Bottom")
	)
	(footprint ""
		(layer "F.Cu")
		(at 323.018404 -337.653376 90)
		(property "Reference" "PC80"
			(at 0 0 90)
			(layer "F.SilkS")
			(hide yes)
			(effects
				(font
					(size 1.27 1.27)
				)
			)
		)
		(property "Value" ""
			(at 0 0 90)
			(layer "F.Fab")
			(effects
				(font
					(size 1.27 1.27)
				)
			)
		)
		(duplicate_pad_numbers_are_jumpers no)
		(fp_line
			(start 0.7874 -0.4064)
			(end 0.7874 0.4064)
			(stroke
				(width 0.1524)
				(type default)
			)
			(layer "F.SilkS")
		)
		(fp_line
			(start -0.7874 -0.4064)
			(end 0.7874 -0.4064)
			(stroke
				(width 0.1524)
				(type default)
			)
			(layer "F.SilkS")
		)
		(fp_line
			(start 0.7874 0.4064)
			(end 0.039624 0.4064)
			(stroke
				(width 0.1524)
				(type default)
			)
			(layer "F.SilkS")
		)
		(fp_line
			(start -0.7874 0.4064)
			(end -0.7874 -0.4064)
			(stroke
				(width 0.1524)
				(type default)
			)
			(layer "F.SilkS")
		)
		(fp_line
			(start -0.12065 -0.305054)
			(end -0.12065 -0.2794)
			(stroke
				(width 0.1)
				(type default)
			)
			(layer "F.Fab")
		)
		(fp_line
			(start -0.67945 -0.305054)
			(end -0.12065 -0.305054)
			(stroke
				(width 0.1)
				(type default)
			)
			(layer "F.Fab")
		)
		(fp_line
			(start 0.67945 -0.3048)
			(end 0.67945 0.3048)
			(stroke
				(width 0.1)
				(type default)
			)
			(layer "F.Fab")
		)
		(fp_line
			(start 0.12065 -0.3048)
			(end 0.67945 -0.3048)
			(stroke
				(width 0.1)
				(type default)
			)
			(layer "F.Fab")
		)
		(fp_line
			(start 0.12065 -0.2794)
			(end 0.12065 -0.3048)
			(stroke
				(width 0.1)
				(type default)
			)
			(layer "F.Fab")
		)
		(fp_line
			(start -0.12065 -0.2794)
			(end 0.12065 -0.2794)
			(stroke
				(width 0.1)
				(type default)
			)
			(layer "F.Fab")
		)
		(fp_line
			(start 0.120396 0.2794)
			(end -0.12065 0.2794)
			(stroke
				(width 0.1)
				(type default)
			)
			(layer "F.Fab")
		)
		(fp_line
			(start -0.12065 0.2794)
			(end -0.12065 0.3048)
			(stroke
				(width 0.1)
				(type default)
			)
			(layer "F.Fab")
		)
		(fp_line
			(start 0.67945 0.3048)
			(end 0.120396 0.3048)
			(stroke
				(width 0.1)
				(type default)
			)
			(layer "F.Fab")
		)
		(fp_line
			(start 0.120396 0.3048)
			(end 0.120396 0.2794)
			(stroke
				(width 0.1)
				(type default)
			)
			(layer "F.Fab")
		)
		(fp_line
			(start -0.12065 0.3048)
			(end -0.67945 0.3048)
			(stroke
				(width 0.1)
				(type default)
			)
			(layer "F.Fab")
		)
		(fp_line
			(start -0.67945 0.3048)
			(end -0.67945 -0.305054)
			(stroke
				(width 0.1)
				(type default)
			)
			(layer "F.Fab")
		)
		(pad "1" smd circle
			(at -0.40005 0 90)
			(size 0 0)
			(layers "F.Cu" "F.Mask" "F.Paste")
			(net "PVDDCR_CPU1_P0_VCC2")
		)
		(pad "2" smd circle
			(at 0.40005 0 90)
			(size 0 0)
			(layers "F.Cu" "F.Mask" "F.Paste")
			(net "GND")
		)
	)
	(footprint ""
		(layer "F.Cu")
		(at 107.677204 -261.748016 -90)
		(property "Reference" "C2262"
			(at 0 0 270)
			(layer "F.SilkS")
			(hide yes)
			(effects
				(font
					(size 1.27 1.27)
				)
			)
		)
		(property "Value" ""
			(at 0 0 270)
			(layer "F.Fab")
			(effects
				(font
					(size 1.27 1.27)
				)
			)
		)
		(duplicate_pad_numbers_are_jumpers no)
		(fp_line
			(start -0.7874 0.4064)
			(end -0.7874 -0.4064)
			(stroke
				(width 0.1524)
				(type default)
			)
			(layer "F.SilkS")
		)
		(fp_line
			(start 0.7874 0.4064)
			(end -0.7874 0.4064)
			(stroke
				(width 0.1524)
				(type default)
			)
			(layer "F.SilkS")
		)
		(fp_line
			(start -0.7874 -0.4064)
			(end 0.7874 -0.4064)
			(stroke
				(width 0.1524)
				(type default)
			)
			(layer "F.SilkS")
		)
		(fp_line
			(start 0.7874 -0.4064)
			(end 0.7874 0.4064)
			(stroke
				(width 0.1524)
				(type default)
			)
			(layer "F.SilkS")
		)
		(fp_line
			(start -0.67945 0.3048)
			(end -0.67945 -0.305054)
			(stroke
				(width 0.1)
				(type default)
			)
			(layer "F.Fab")
		)
		(fp_line
			(start -0.12065 0.3048)
			(end -0.67945 0.3048)
			(stroke
				(width 0.1)
				(type default)
			)
			(layer "F.Fab")
		)
		(fp_line
			(start 0.120396 0.3048)
			(end 0.120396 0.2794)
			(stroke
				(width 0.1)
				(type default)
			)
			(layer "F.Fab")
		)
		(fp_line
			(start 0.67945 0.3048)
			(end 0.120396 0.3048)
			(stroke
				(width 0.1)
				(type default)
			)
			(layer "F.Fab")
		)
		(fp_line
			(start -0.12065 0.2794)
			(end -0.12065 0.3048)
			(stroke
				(width 0.1)
				(type default)
			)
			(layer "F.Fab")
		)
		(fp_line
			(start 0.120396 0.2794)
			(end -0.12065 0.2794)
			(stroke
				(width 0.1)
				(type default)
			)
			(layer "F.Fab")
		)
		(fp_line
			(start -0.12065 -0.2794)
			(end 0.12065 -0.2794)
			(stroke
				(width 0.1)
				(type default)
			)
			(layer "F.Fab")
		)
		(fp_line
			(start 0.12065 -0.2794)
			(end 0.12065 -0.3048)
			(stroke
				(width 0.1)
				(type default)
			)
			(layer "F.Fab")
		)
		(fp_line
			(start 0.12065 -0.3048)
			(end 0.67945 -0.3048)
			(stroke
				(width 0.1)
				(type default)
			)
			(layer "F.Fab")
		)
		(fp_line
			(start 0.67945 -0.3048)
			(end 0.67945 0.3048)
			(stroke
				(width 0.1)
				(type default)
			)
			(layer "F.Fab")
		)
		(fp_line
			(start -0.67945 -0.305054)
			(end -0.12065 -0.305054)
			(stroke
				(width 0.1)
				(type default)
			)
			(layer "F.Fab")
		)
		(fp_line
			(start -0.12065 -0.305054)
			(end -0.12065 -0.2794)
			(stroke
				(width 0.1)
				(type default)
			)
			(layer "F.Fab")
		)
		(pad "1" smd circle
			(at -0.40005 0 270)
			(size 0 0)
			(layers "F.Cu" "F.Mask" "F.Paste")
			(net "PVDD11_S3_P1")
		)
		(pad "2" smd circle
			(at 0.40005 0 270)
			(size 0 0)
			(layers "F.Cu" "F.Mask" "F.Paste")
			(net "GND")
		)
	)
)
